FILE_TYPE = CONNECTIVITY;
{Allegro Design Entry HDL 17.4-2019 S026 (4007227) 1/17/2022}
"PAGE_NUMBER" = 359;
0"NC";
1"GND\g";
2"GND\g";
3"GND\g";
4"GND\g";
5"GND\g";
6"GND\g";
7"GND\g";
8"GND\g";
9"GND\g";
10"GND\g";
11"GND\g";
12"GND\g";
13"GND\g";
14"P3V3_AUX\g";
15"P3V3_AUX\g";
16"P3V3_AUX\g";
17"P3V3_AUX\g";
18"GND\g";
19"GND\g";
20"GND\g";
21"GND\g";
22"GND\g";
23"GND\g";
24"GND\g";
25"P3V3_AUX\g"VOLTAGE"3.3";
26"U273_3_ADD1"CDS_PHYS_NET_NAME"TCA9539_0_ADD1";
27"U273_3_ADD0"CDS_PHYS_NET_NAME"TCA9539_0_ADD0";
28"U273_3_ADD2"CDS_PHYS_NET_NAME"TCA9539_0_ADD1";
29"U271_1_ADD2"CDS_PHYS_NET_NAME"TCA9539_0_ADD1";
30"U271_1_ADD1"CDS_PHYS_NET_NAME"TCA9539_0_ADD1";
31"P3V3_AUX\g";
32"FM_LM75_2_ALERT_N";
33"SMB_LM75_2_3V3AUX_SCL_R1";
34"P3V3_AUX\g";
35"P3V3_AUX\g";
36"P3V3_AUX\g";
37"P3V3_AUX\g";
38"P3V3_AUX\g"VOLTAGE"3.3";
39"P3V3_AUX\g";
40"U272_2_ADD2"CDS_PHYS_NET_NAME"TCA9539_0_ADD1";
41"U272_2_ADD0"CDS_PHYS_NET_NAME"TCA9539_0_ADD0";
42"SMB_LM75_0_3V3AUX_SDA_R1";
43"SMB_LM75_0_3V3AUX_SCL_R1";
44"U271_1_ADD0"CDS_PHYS_NET_NAME"TCA9539_0_ADD0";
45"FM_G751_1_ALERT_N";
46"U270_0_ADD2"CDS_PHYS_NET_NAME"TCA9539_0_ADD1";
47"U270_0_ADD1"CDS_PHYS_NET_NAME"TCA9539_0_ADD1";
48"U270_0_ADD0"CDS_PHYS_NET_NAME"TCA9539_0_ADD0";
49"SMB_LM75_1_3V3AUX_SDA_R1";
50"FM_G751_0_ALERT_N";
51"U272_2_ADD1"CDS_PHYS_NET_NAME"TCA9539_0_ADD1";
52"SMB_LM75_0_3V3AUX_SCL";
53"SMB_LM75_1_3V3AUX_SCL";
54"SMB_LM75_2_3V3AUX_SCL";
55"SMB_LM75_2_3V3AUX_SDA";
56"SMB_LM75_3_3V3AUX_SCL";
57"FM_LM75_3_ALERT_N";
58"SMB_LM75_3_3V3AUX_SDA_R1";
59"SMB_LM75_3_3V3AUX_SCL_R1";
60"SMB_LM75_3_3V3AUX_SDA";
61"SMB_LM75_2_3V3AUX_SDA_R1";
62"SMB_LM75_1_3V3AUX_SCL_R1";
63"SMB_LM75_1_3V3AUX_SDA";
64"FM_THERMAL_ALERT_N";
65"SMB_LM75_0_3V3AUX_SDA";
66"FM_THERMAL_ALERT_N";
67"FM_THERMAL_ALERT_N";
68"FM_THERMAL_ALERT_N";
%"UNIVERSAL_POWER"
"1","(2550,800)","0","pure_quanta_power","I100";
;
HDL_POWER"P3V3_AUX"
CDS_LIB"pure_quanta_power";
"A"39;
%"Q_RES"
"2","(3900,125)","0","pure_quanta","I101";
;
LOCATION"R4188"
$SEC"1"
CDS_SEC"1"
PACK_TYPE"0402LF"
MATERIAL"EMPTY"
VALUE"1K"
WATTAGE"1/16W"
TOLERANCE"1%"
CDS_LIB"pure_quanta"
PART_NUMBER"CS21002FB06";
"A"
$PN"1"31;
"B"
$PN"2"29;
%"Q_RES"
"2","(3900,-475)","0","pure_quanta","I102";
;
LOCATION"R4189"
$SEC"1"
CDS_SEC"1"
TOLERANCE"1%"
WATTAGE"1/16W"
VALUE"1K"
PACK_TYPE"0402LF"
MATERIAL"CHIP"
CDS_LIB"pure_quanta"
PART_NUMBER"CS21002FB06";
"A"
$PN"1"29;
"B"
$PN"2"1;
%"UNIVERSAL_GND"
"1","(3900,-700)","0","pure_quanta_power","I103";
;
CDS_LIB"pure_quanta_power"
HDL_POWER"GND";
"A"1;
%"Q_CAP"
"1","(2550,475)","2","pure_quanta","I104";
;
LOCATION"C73"
$SEC"1"
CDS_SEC"1"
VOLTAGE"25V"
MATERIAL"X7R"
PACK_TYPE"0402"
VALUE"0.1UF"
TOLERANCE"10%"
CDS_LIB"pure_quanta"
PART_NUMBER"CH4104K1B00";
"B"
$PN"2"2;
"A"
$PN"1"39;
%"UNIVERSAL_GND"
"1","(2550,250)","0","pure_quanta_power","I105";
;
CDS_LIB"pure_quanta_power"
HDL_POWER"GND";
"A"2;
%"UNIVERSAL_GND"
"1","(1625,-450)","0","pure_quanta_power","I106";
;
CDS_LIB"pure_quanta_power"
HDL_POWER"GND";
"A"3;
%"Q_RES"
"1","(300,125)","0","pure_quanta","I107";
;
LOCATION"R4182"
$SEC"1"
CDS_SEC"1"
PACK_TYPE"0402LF"
VALUE"33.2"
TOLERANCE"1%"
MATERIAL"CHIP"
WATTAGE"1/16W"
CDS_LIB"pure_quanta"
PART_NUMBER"CS03322FB03";
"B"
$PN"2"49;
"A"
$PN"1"63;
%"Q_RES"
"1","(300,-175)","0","pure_quanta","I108";
;
LOCATION"R4214"
$SEC"1"
CDS_SEC"1"
MATERIAL"CHIP"
PACK_TYPE"0402LF"
VALUE"0"
TOLERANCE"5%"
WATTAGE"1/16W"
CDS_LIB"pure_quanta"
PART_NUMBER"CS00002JB13";
"B"
$PN"2"45;
"A"
$PN"1"66;
%"Q_RES"
"1","(300,-25)","0","pure_quanta","I109";
;
LOCATION"R4179"
$SEC"1"
CDS_SEC"1"
PACK_TYPE"0402LF"
WATTAGE"1/16W"
TOLERANCE"1%"
VALUE"33.2"
MATERIAL"CHIP"
CDS_LIB"pure_quanta"
PART_NUMBER"CS03322FB03";
"B"
$PN"2"62;
"A"
$PN"1"53;
%"Q_RES"
"1","(275,-1500)","0","pure_quanta","I114";
;
LOCATION"R4178"
$SEC"1"
CDS_SEC"1"
VALUE"33.2"
PACK_TYPE"0402LF"
MATERIAL"CHIP"
WATTAGE"1/16W"
TOLERANCE"1%"
CDS_LIB"pure_quanta"
PART_NUMBER"CS03322FB03";
"B"
$PN"2"33;
"A"
$PN"1"54;
%"Q_RES"
"1","(275,-1650)","0","pure_quanta","I115";
;
LOCATION"R4213"
$SEC"1"
CDS_SEC"1"
PACK_TYPE"0402LF"
VALUE"0"
MATERIAL"CHIP"
CDS_LIB"pure_quanta"
WATTAGE"1/16W"
TOLERANCE"5%"
PART_NUMBER"CS00002JB13";
"B"
$PN"2"32;
"A"
$PN"1"67;
%"Q_RES"
"1","(275,-1350)","0","pure_quanta","I116";
;
LOCATION"R4181"
$SEC"1"
CDS_SEC"1"
PACK_TYPE"0402LF"
WATTAGE"1/16W"
TOLERANCE"1%"
VALUE"33.2"
MATERIAL"CHIP"
CDS_LIB"pure_quanta"
PART_NUMBER"CS03322FB03";
"B"
$PN"2"61;
"A"
$PN"1"55;
%"UNIVERSAL_GND"
"1","(1600,-1925)","0","pure_quanta_power","I117";
;
CDS_LIB"pure_quanta_power"
HDL_POWER"GND";
"A"4;
%"UNIVERSAL_GND"
"1","(2525,-1225)","0","pure_quanta_power","I118";
;
CDS_LIB"pure_quanta_power"
HDL_POWER"GND";
"A"5;
%"Q_CAP"
"1","(2525,-1000)","2","pure_quanta","I119";
;
LOCATION"C32"
$SEC"1"
CDS_SEC"1"
PACK_TYPE"0402"
VALUE"0.1UF"
VOLTAGE"25V"
TOLERANCE"10%"
MATERIAL"X7R"
CDS_LIB"pure_quanta"
PART_NUMBER"CH4104K1B00";
"B"
$PN"2"5;
"A"
$PN"1"38;
%"UNIVERSAL_GND"
"1","(3875,-2175)","0","pure_quanta_power","I120";
;
CDS_LIB"pure_quanta_power"
HDL_POWER"GND";
"A"6;
%"Q_RES"
"2","(3875,-1950)","0","pure_quanta","I121";
;
LOCATION"R4187"
$SEC"1"
CDS_SEC"1"
MATERIAL"CHIP"
PACK_TYPE"0402LF"
VALUE"1K"
WATTAGE"1/16W"
TOLERANCE"1%"
CDS_LIB"pure_quanta"
PART_NUMBER"CS21002FB06";
"A"
$PN"1"40;
"B"
$PN"2"6;
%"Q_RES"
"2","(3875,-1350)","0","pure_quanta","I122";
;
LOCATION"R4186"
$SEC"1"
CDS_SEC"1"
TOLERANCE"1%"
WATTAGE"1/16W"
VALUE"1K"
MATERIAL"EMPTY"
PACK_TYPE"0402LF"
CDS_LIB"pure_quanta"
PART_NUMBER"CS21002FB06";
"A"
$PN"1"37;
"B"
$PN"2"40;
%"UNIVERSAL_POWER"
"1","(2525,-675)","0","pure_quanta_power","I123";
;
HDL_POWER"P3V3_AUX"
CDS_LIB"pure_quanta_power";
"A"38;
%"UNIVERSAL_GND"
"1","(4125,-2175)","0","pure_quanta_power","I124";
;
CDS_LIB"pure_quanta_power"
HDL_POWER"GND";
"A"7;
%"Q_RES"
"2","(4125,-1950)","0","pure_quanta","I125";
;
LOCATION"R4195"
$SEC"1"
CDS_SEC"1"
MATERIAL"CHIP"
PACK_TYPE"0402LF"
VALUE"1K"
WATTAGE"1/16W"
TOLERANCE"1%"
CDS_LIB"pure_quanta"
PART_NUMBER"CS21002FB06";
"A"
$PN"1"51;
"B"
$PN"2"7;
%"UNIVERSAL_GND"
"1","(4375,-2175)","0","pure_quanta_power","I126";
;
CDS_LIB"pure_quanta_power"
HDL_POWER"GND";
"A"8;
%"Q_RES"
"2","(4375,-1950)","0","pure_quanta","I127";
;
LOCATION"R4203"
$SEC"1"
CDS_SEC"1"
MATERIAL"CHIP"
PACK_TYPE"0402LF"
WATTAGE"1/16W"
VALUE"1K"
TOLERANCE"1%"
CDS_LIB"pure_quanta"
PART_NUMBER"CS21002FB06";
"A"
$PN"1"41;
"B"
$PN"2"8;
%"Q_RES"
"2","(4125,-1350)","0","pure_quanta","I128";
;
LOCATION"R4194"
$SEC"1"
CDS_SEC"1"
TOLERANCE"1%"
WATTAGE"1/16W"
VALUE"1K"
MATERIAL"EMPTY"
PACK_TYPE"0402LF"
CDS_LIB"pure_quanta"
PART_NUMBER"CS21002FB06";
"A"
$PN"1"37;
"B"
$PN"2"51;
%"Q_RES"
"2","(4375,-1350)","0","pure_quanta","I129";
;
LOCATION"R4202"
$SEC"1"
CDS_SEC"1"
WATTAGE"1/16W"
VALUE"1K"
PACK_TYPE"0402LF"
TOLERANCE"1%"
MATERIAL"EMPTY"
CDS_LIB"pure_quanta"
PART_NUMBER"CS21002FB06";
"A"
$PN"1"37;
"B"
$PN"2"41;
%"UNIVERSAL_POWER"
"1","(4375,-925)","0","pure_quanta_power","I130";
;
HDL_POWER"P3V3_AUX"
CDS_LIB"pure_quanta_power";
"A"37;
%"Q_RES"
"1","(225,-2975)","0","pure_quanta","I134";
;
LOCATION"R3553"
$SEC"1"
CDS_SEC"1"
TOLERANCE"1%"
WATTAGE"1/16W"
VALUE"33.2"
PACK_TYPE"0402LF"
MATERIAL"CHIP"
CDS_LIB"pure_quanta"
PART_NUMBER"CS03322FB03";
"B"
$PN"2"59;
"A"
$PN"1"56;
%"Q_RES"
"1","(225,-3125)","0","pure_quanta","I135";
;
LOCATION"R4212"
$SEC"1"
CDS_SEC"1"
VALUE"0"
PACK_TYPE"0402LF"
MATERIAL"CHIP"
TOLERANCE"5%"
WATTAGE"1/16W"
CDS_LIB"pure_quanta"
PART_NUMBER"CS00002JB13";
"B"
$PN"2"57;
"A"
$PN"1"68;
%"Q_RES"
"1","(225,-2825)","0","pure_quanta","I136";
;
LOCATION"R3554"
$SEC"1"
CDS_SEC"1"
WATTAGE"1/16W"
MATERIAL"CHIP"
TOLERANCE"1%"
PACK_TYPE"0402LF"
VALUE"33.2"
CDS_LIB"pure_quanta"
PART_NUMBER"CS03322FB03";
"B"
$PN"2"58;
"A"
$PN"1"60;
%"UNIVERSAL_GND"
"1","(1550,-3400)","0","pure_quanta_power","I137";
;
CDS_LIB"pure_quanta_power"
HDL_POWER"GND";
"A"9;
%"UNIVERSAL_GND"
"1","(2475,-2700)","0","pure_quanta_power","I138";
;
CDS_LIB"pure_quanta_power"
HDL_POWER"GND";
"A"10;
%"Q_CAP"
"1","(2475,-2475)","2","pure_quanta","I139";
;
LOCATION"C31"
$SEC"1"
CDS_SEC"1"
VALUE"0.1UF"
TOLERANCE"10%"
PACK_TYPE"0402"
MATERIAL"X7R"
VOLTAGE"25V"
CDS_LIB"pure_quanta"
PART_NUMBER"CH4104K1B00";
"B"
$PN"2"10;
"A"
$PN"1"25;
%"UNIVERSAL_GND"
"1","(3825,-3650)","0","pure_quanta_power","I140";
;
CDS_LIB"pure_quanta_power"
HDL_POWER"GND";
"A"11;
%"Q_RES"
"2","(3825,-3425)","0","pure_quanta","I141";
;
LOCATION"R4185"
$SEC"1"
CDS_SEC"1"
TOLERANCE"1%"
WATTAGE"1/16W"
VALUE"1K"
PACK_TYPE"0402LF"
MATERIAL"CHIP"
CDS_LIB"pure_quanta"
PART_NUMBER"CS21002FB06";
"A"
$PN"1"28;
"B"
$PN"2"11;
%"Q_RES"
"2","(3825,-2825)","0","pure_quanta","I142";
;
LOCATION"R4184"
$SEC"1"
CDS_SEC"1"
MATERIAL"EMPTY"
PACK_TYPE"0402LF"
TOLERANCE"1%"
VALUE"1K"
WATTAGE"1/16W"
CDS_LIB"pure_quanta"
PART_NUMBER"CS21002FB06";
"A"
$PN"1"35;
"B"
$PN"2"28;
%"UNIVERSAL_POWER"
"1","(2475,-2150)","0","pure_quanta_power","I143";
;
HDL_POWER"P3V3_AUX"
CDS_LIB"pure_quanta_power";
"A"25;
%"UNIVERSAL_GND"
"1","(4075,-3650)","0","pure_quanta_power","I144";
;
CDS_LIB"pure_quanta_power"
HDL_POWER"GND";
"A"12;
%"Q_RES"
"2","(4075,-3425)","0","pure_quanta","I145";
;
LOCATION"R4193"
$SEC"1"
CDS_SEC"1"
TOLERANCE"1%"
WATTAGE"1/16W"
VALUE"1K"
PACK_TYPE"0402LF"
MATERIAL"CHIP"
CDS_LIB"pure_quanta"
PART_NUMBER"CS21002FB06";
"A"
$PN"1"26;
"B"
$PN"2"12;
%"UNIVERSAL_GND"
"1","(4325,-3650)","0","pure_quanta_power","I146";
;
CDS_LIB"pure_quanta_power"
HDL_POWER"GND";
"A"13;
%"Q_RES"
"2","(4325,-3425)","0","pure_quanta","I147";
;
LOCATION"R4201"
$SEC"1"
CDS_SEC"1"
TOLERANCE"1%"
VALUE"1K"
WATTAGE"1/16W"
PACK_TYPE"0402LF"
MATERIAL"CHIP"
CDS_LIB"pure_quanta"
PART_NUMBER"CS21002FB06";
"A"
$PN"1"27;
"B"
$PN"2"13;
%"Q_RES"
"2","(4075,-2825)","0","pure_quanta","I148";
;
LOCATION"R4192"
$SEC"1"
CDS_SEC"1"
MATERIAL"EMPTY"
PACK_TYPE"0402LF"
VALUE"1K"
WATTAGE"1/16W"
TOLERANCE"1%"
CDS_LIB"pure_quanta"
PART_NUMBER"CS21002FB06";
"A"
$PN"1"35;
"B"
$PN"2"26;
%"Q_RES"
"2","(4325,-2825)","0","pure_quanta","I149";
;
LOCATION"R4200"
$SEC"1"
CDS_SEC"1"
MATERIAL"EMPTY"
TOLERANCE"1%"
PACK_TYPE"0402LF"
VALUE"1K"
WATTAGE"1/16W"
CDS_LIB"pure_quanta"
PART_NUMBER"CS21002FB06";
"A"
$PN"1"35;
"B"
$PN"2"27;
%"UNIVERSAL_POWER"
"1","(2600,2275)","0","pure_quanta_power","I15";
;
HDL_POWER"P3V3_AUX"
CDS_LIB"pure_quanta_power";
"A"36;
%"UNIVERSAL_POWER"
"1","(4325,-2400)","0","pure_quanta_power","I150";
;
HDL_POWER"P3V3_AUX"
CDS_LIB"pure_quanta_power";
"A"35;
%"UNIVERSAL_POWER"
"1","(-200,2025)","0","pure_quanta_power","I153";
;
HDL_POWER"P3V3_AUX"
CDS_LIB"pure_quanta_power";
"A"14;
%"UNIVERSAL_POWER"
"1","(-250,550)","0","pure_quanta_power","I154";
;
HDL_POWER"P3V3_AUX"
CDS_LIB"pure_quanta_power";
"A"15;
%"UNIVERSAL_POWER"
"1","(-250,-925)","0","pure_quanta_power","I156";
;
HDL_POWER"P3V3_AUX"
CDS_LIB"pure_quanta_power";
"A"16;
%"UNIVERSAL_POWER"
"1","(-350,-2350)","0","pure_quanta_power","I159";
;
HDL_POWER"P3V3_AUX"
CDS_LIB"pure_quanta_power";
"A"17;
%"Q_CAP"
"1","(2600,1950)","2","pure_quanta","I16";
;
LOCATION"C2010"
$SEC"1"
CDS_SEC"1"
MATERIAL"X7R"
TOLERANCE"10%"
VOLTAGE"25V"
PACK_TYPE"0402"
VALUE"0.1UF"
CDS_LIB"pure_quanta"
PART_NUMBER"CH4104K1B00";
"B"
$PN"2"18;
"A"
$PN"1"36;
%"LM75BD"
"1","(2150,1375)","0","pure_quanta","I164";
;
LOCATION"U270"
$SEC"1"
CDS_SEC"1"
PART_TYPE"SMLF"
VALUE"LM75BD"
MATERIAL"IC"
CDS_LIB"pure_quanta"
CDS_LMAN_SYM_OUTLINE"-225,325,225,-325"
NEEDS_NO_SIZE"TRUE"
PART_NUMBER"AL0075BD000";
"VCC"
$PN"8"36;
"A0"
$PN"7"48;
"A1"
$PN"6"47;
"A2"
$PN"5"46;
"GND"
$PN"4"19;
"OS"
$PN"3"50;
"SCL"
$PN"2"43;
"SDA"
$PN"1"42;
%"LM75BD"
"1","(2100,-100)","0","pure_quanta","I165";
;
LOCATION"U271"
$SEC"1"
CDS_SEC"1"
MATERIAL"IC"
PART_TYPE"SMLF"
VALUE"LM75BD"
CDS_LMAN_SYM_OUTLINE"-225,325,225,-325"
CDS_LIB"pure_quanta"
NEEDS_NO_SIZE"TRUE"
PART_NUMBER"AL0075BD000";
"VCC"
$PN"8"39;
"A0"
$PN"7"44;
"A1"
$PN"6"30;
"A2"
$PN"5"29;
"GND"
$PN"4"3;
"OS"
$PN"3"45;
"SCL"
$PN"2"62;
"SDA"
$PN"1"49;
%"LM75BD"
"1","(2075,-1575)","0","pure_quanta","I166";
;
LOCATION"U272"
$SEC"1"
CDS_SEC"1"
VALUE"LM75BD"
MATERIAL"IC"
PART_TYPE"SMLF"
CDS_LIB"pure_quanta"
CDS_LMAN_SYM_OUTLINE"-225,325,225,-325"
NEEDS_NO_SIZE"TRUE"
PART_NUMBER"AL0075BD000";
"VCC"
$PN"8"38;
"A0"
$PN"7"41;
"A1"
$PN"6"51;
"A2"
$PN"5"40;
"GND"
$PN"4"4;
"OS"
$PN"3"32;
"SCL"
$PN"2"33;
"SDA"
$PN"1"61;
%"LM75BD"
"1","(2025,-3050)","0","pure_quanta","I167";
;
LOCATION"U273"
$SEC"1"
CDS_SEC"1"
VALUE"LM75BD"
PART_TYPE"SMLF"
MATERIAL"IC"
NEEDS_NO_SIZE"TRUE"
CDS_LMAN_SYM_OUTLINE"-225,325,225,-325"
CDS_LIB"pure_quanta"
PART_NUMBER"AL0075BD000";
"VCC"
$PN"8"25;
"A0"
$PN"7"27;
"A1"
$PN"6"26;
"A2"
$PN"5"28;
"GND"
$PN"4"9;
"OS"
$PN"3"57;
"SCL"
$PN"2"59;
"SDA"
$PN"1"58;
%"Q_RES"
"2","(-200,1800)","0","pure_quanta","I168";
;
LOCATION"R4211"
$SEC"1"
CDS_SEC"1"
VALUE"200K"
PACK_TYPE"0402LF"
MATERIAL"CHIP"
WATTAGE"1/16W"
TOLERANCE"1%"
CDS_LIB"pure_quanta"
PART_NUMBER"CS42002FB05";
"A"
$PN"1"14;
"B"
$PN"2"64;
%"Q_RES"
"2","(-250,325)","0","pure_quanta","I169";
;
LOCATION"R4209"
$SEC"1"
CDS_SEC"1"
MATERIAL"EMPTY"
WATTAGE"1/16W"
PACK_TYPE"0402LF"
TOLERANCE"1%"
VALUE"200K"
CDS_LIB"pure_quanta"
PART_NUMBER"CS42002FB05";
"A"
$PN"1"15;
"B"
$PN"2"66;
%"UNIVERSAL_GND"
"1","(2600,1725)","0","pure_quanta_power","I17";
;
CDS_LIB"pure_quanta_power"
HDL_POWER"GND";
"A"18;
%"Q_RES"
"2","(-250,-1175)","0","pure_quanta","I170";
;
LOCATION"R4210"
$SEC"1"
CDS_SEC"1"
VALUE"200K"
TOLERANCE"1%"
PACK_TYPE"0402LF"
WATTAGE"1/16W"
MATERIAL"EMPTY"
CDS_LIB"pure_quanta"
PART_NUMBER"CS42002FB05";
"A"
$PN"1"16;
"B"
$PN"2"67;
%"Q_RES"
"2","(-350,-2625)","0","pure_quanta","I171";
;
LOCATION"R4208"
$SEC"1"
CDS_SEC"1"
PACK_TYPE"0402LF"
MATERIAL"EMPTY"
WATTAGE"1/16W"
TOLERANCE"1%"
VALUE"200K"
CDS_LIB"pure_quanta"
PART_NUMBER"CS42002FB05";
"A"
$PN"1"17;
"B"
$PN"2"68;
%"UNIVERSAL_GND"
"1","(1675,1025)","0","pure_quanta_power","I21";
;
CDS_LIB"pure_quanta_power"
HDL_POWER"GND";
"A"19;
%"Q_RES"
"1","(350,1450)","0","pure_quanta","I77";
;
LOCATION"R4180"
$SEC"1"
CDS_SEC"1"
PACK_TYPE"0402LF"
TOLERANCE"1%"
WATTAGE"1/16W"
MATERIAL"CHIP"
VALUE"33.2"
CDS_LIB"pure_quanta"
PART_NUMBER"CS03322FB03";
"B"
$PN"2"43;
"A"
$PN"1"52;
%"Q_RES"
"1","(350,1600)","0","pure_quanta","I78";
;
LOCATION"R4183"
$SEC"1"
CDS_SEC"1"
WATTAGE"1/16W"
MATERIAL"CHIP"
TOLERANCE"1%"
VALUE"33.2"
PACK_TYPE"0402LF"
CDS_LIB"pure_quanta"
PART_NUMBER"CS03322FB03";
"B"
$PN"2"42;
"A"
$PN"1"65;
%"Q_RES"
"1","(350,1300)","0","pure_quanta","I79";
;
LOCATION"R4215"
$SEC"1"
CDS_SEC"1"
VALUE"0"
MATERIAL"CHIP"
PACK_TYPE"0402LF"
CDS_LIB"pure_quanta"
WATTAGE"1/16W"
TOLERANCE"5%"
PART_NUMBER"CS00002JB13";
"B"
$PN"2"50;
"A"
$PN"1"64;
%"UNIVERSAL_GND"
"1","(4200,775)","0","pure_quanta_power","I80";
;
CDS_LIB"pure_quanta_power"
HDL_POWER"GND";
"A"20;
%"Q_RES"
"2","(4200,1000)","0","pure_quanta","I81";
;
LOCATION"R4199"
$SEC"1"
CDS_SEC"1"
TOLERANCE"1%"
WATTAGE"1/16W"
VALUE"1K"
PACK_TYPE"0402LF"
MATERIAL"CHIP"
CDS_LIB"pure_quanta"
PART_NUMBER"CS21002FB06";
"A"
$PN"1"47;
"B"
$PN"2"20;
%"Q_RES"
"2","(4200,1600)","0","pure_quanta","I82";
;
LOCATION"R4198"
$SEC"1"
CDS_SEC"1"
PACK_TYPE"0402LF"
VALUE"1K"
TOLERANCE"1%"
MATERIAL"EMPTY"
WATTAGE"1/16W"
CDS_LIB"pure_quanta"
PART_NUMBER"CS21002FB06";
"A"
$PN"1"34;
"B"
$PN"2"47;
%"UNIVERSAL_POWER"
"1","(4450,2025)","0","pure_quanta_power","I83";
;
HDL_POWER"P3V3_AUX"
CDS_LIB"pure_quanta_power";
"A"34;
%"UNIVERSAL_GND"
"1","(4450,775)","0","pure_quanta_power","I84";
;
CDS_LIB"pure_quanta_power"
HDL_POWER"GND";
"A"21;
%"Q_RES"
"2","(4450,1000)","0","pure_quanta","I85";
;
LOCATION"R4207"
$SEC"1"
CDS_SEC"1"
TOLERANCE"1%"
VALUE"1K"
WATTAGE"1/16W"
PACK_TYPE"0402LF"
MATERIAL"CHIP"
CDS_LIB"pure_quanta"
PART_NUMBER"CS21002FB06";
"A"
$PN"1"48;
"B"
$PN"2"21;
%"Q_RES"
"2","(4450,1600)","0","pure_quanta","I86";
;
LOCATION"R4206"
$SEC"1"
CDS_SEC"1"
TOLERANCE"1%"
VALUE"1K"
WATTAGE"1/16W"
MATERIAL"EMPTY"
PACK_TYPE"0402LF"
CDS_LIB"pure_quanta"
PART_NUMBER"CS21002FB06";
"A"
$PN"1"34;
"B"
$PN"2"48;
%"Q_RES"
"2","(3950,1000)","0","pure_quanta","I89";
;
LOCATION"R4191"
$SEC"1"
CDS_SEC"1"
PACK_TYPE"0402LF"
MATERIAL"CHIP"
VALUE"1K"
TOLERANCE"1%"
WATTAGE"1/16W"
CDS_LIB"pure_quanta"
PART_NUMBER"CS21002FB06";
"A"
$PN"1"46;
"B"
$PN"2"22;
%"UNIVERSAL_GND"
"1","(3950,775)","0","pure_quanta_power","I90";
;
CDS_LIB"pure_quanta_power"
HDL_POWER"GND";
"A"22;
%"Q_RES"
"2","(3950,1600)","0","pure_quanta","I91";
;
LOCATION"R4190"
$SEC"1"
CDS_SEC"1"
MATERIAL"EMPTY"
TOLERANCE"1%"
VALUE"1K"
WATTAGE"1/16W"
PACK_TYPE"0402LF"
CDS_LIB"pure_quanta"
PART_NUMBER"CS21002FB06";
"A"
$PN"1"34;
"B"
$PN"2"46;
%"UNIVERSAL_POWER"
"1","(4400,550)","0","pure_quanta_power","I93";
;
HDL_POWER"P3V3_AUX"
CDS_LIB"pure_quanta_power";
"A"31;
%"Q_RES"
"2","(4400,125)","0","pure_quanta","I94";
;
LOCATION"R4204"
$SEC"1"
CDS_SEC"1"
MATERIAL"EMPTY"
TOLERANCE"1%"
PACK_TYPE"0402LF"
VALUE"1K"
WATTAGE"1/16W"
CDS_LIB"pure_quanta"
PART_NUMBER"CS21002FB06";
"A"
$PN"1"31;
"B"
$PN"2"44;
%"Q_RES"
"2","(4150,125)","0","pure_quanta","I95";
;
LOCATION"R4196"
$SEC"1"
CDS_SEC"1"
PACK_TYPE"0402LF"
MATERIAL"EMPTY"
VALUE"1K"
WATTAGE"1/16W"
TOLERANCE"1%"
CDS_LIB"pure_quanta"
PART_NUMBER"CS21002FB06";
"A"
$PN"1"31;
"B"
$PN"2"30;
%"Q_RES"
"2","(4400,-475)","0","pure_quanta","I96";
;
LOCATION"R4205"
$SEC"1"
CDS_SEC"1"
TOLERANCE"1%"
VALUE"1K"
WATTAGE"1/16W"
PACK_TYPE"0402LF"
MATERIAL"CHIP"
CDS_LIB"pure_quanta"
PART_NUMBER"CS21002FB06";
"A"
$PN"1"44;
"B"
$PN"2"23;
%"UNIVERSAL_GND"
"1","(4400,-700)","0","pure_quanta_power","I97";
;
CDS_LIB"pure_quanta_power"
HDL_POWER"GND";
"A"23;
%"Q_RES"
"2","(4150,-475)","0","pure_quanta","I98";
;
LOCATION"R4197"
$SEC"1"
CDS_SEC"1"
WATTAGE"1/16W"
VALUE"1K"
PACK_TYPE"0402LF"
MATERIAL"CHIP"
TOLERANCE"1%"
CDS_LIB"pure_quanta"
PART_NUMBER"CS21002FB06";
"A"
$PN"1"30;
"B"
$PN"2"24;
%"UNIVERSAL_GND"
"1","(4150,-700)","0","pure_quanta_power","I99";
;
CDS_LIB"pure_quanta_power"
HDL_POWER"GND";
"A"24;
END.
